FILE_TYPE=LIBRARY_PARTS;
primitive 'AP22811AW57';
  pin
    'OUT':
      PIN_NUMBER='(1)';
      OUTPUT_LOAD='(1.0,-1.0)';
    'GND':
      PIN_NUMBER='(2)';
      PINUSE='POWER';
      NO_LOAD_CHECK='Both';
      NO_IO_CHECK='Both';
      NO_ASSERT_CHECK='TRUE';
      NO_DIR_CHECK='TRUE';
      ALLOW_CONNECT='TRUE';
    'EN':
      PIN_NUMBER='(4)';
      INPUT_LOAD='(-0.01,0.01)';
    'FLG#':
      PIN_NUMBER='(3)';
      OUTPUT_TYPE='(OC,AND)';
      OUTPUT_LOAD='(1.0,*)';
    'IN':
      PIN_NUMBER='(5)';
      INPUT_LOAD='(-0.01,0.01)';
  end_pin;
  body
    PART_NAME='AP22811AW57';
    BODY_NAME='AP22811AW57';
    PHYS_DES_PREFIX='U';
    CLASS='IC';
  end_body;
end_primitive;

END.
